(kicad_pcb
	(version 20260206)
	(generator "pcbnew")
	(generator_version "10.0")
	(general
		(thickness 1.6)
		(legacy_teardrops no)
	)
	(paper "A4")
	(title_block
		(title "01162023_DA0F0TEBIF0_F0T_Expander_BD_F_brd_V02_OCP.brd")
		(comment 1 "Grand Teton / footprints 6437-6442 of 9728")
	)
	(layers
		(0 "F.Cu" signal "TOP")
		(4 "In1.Cu" signal "GND")
		(6 "In2.Cu" signal "VCC")
		(8 "In3.Cu" signal "VCC1")
		(10 "In4.Cu" signal "GND1")
		(12 "In5.Cu" signal "IN1")
		(14 "In6.Cu" signal "GND2")
		(16 "In7.Cu" signal "IN2")
		(18 "In8.Cu" signal "GND3")
		(20 "In9.Cu" signal "IN3")
		(22 "In10.Cu" signal "GND4")
		(24 "In11.Cu" signal "IN4")
		(26 "In12.Cu" signal "GND5")
		(28 "In13.Cu" signal "IN5")
		(30 "In14.Cu" signal "GND6")
		(32 "In15.Cu" signal "IN6")
		(34 "In16.Cu" signal "GND7")
		(2 "B.Cu" signal "BOTTOM")
		(9 "F.Adhes" user "F.Adhesive")
		(11 "B.Adhes" user "B.Adhesive")
		(13 "F.Paste" user "Package Geometry/Pastemask Top")
		(15 "B.Paste" user "Package Geometry/Pastemask Bottom")
		(5 "F.SilkS" user "Ref Des/Silkscreen Top")
		(7 "B.SilkS" user "Ref Des/Silkscreen Bottom")
		(1 "F.Mask" user "Board Geometry/Soldermask Top")
		(3 "B.Mask" user "Board Geometry/Soldermask Bottom")
		(17 "Dwgs.User" user "User.Drawings")
		(19 "Cmts.User" user "User.Comments")
		(21 "Eco1.User" user "User.Eco1")
		(23 "Eco2.User" user "User.Eco2")
		(25 "Edge.Cuts" user "Board Geometry/Outline")
		(27 "Margin" user)
		(31 "F.CrtYd" user "Package Geometry/Place Bound Top")
		(29 "B.CrtYd" user "Package Geometry/Place Bound Bottom")
		(35 "F.Fab" user "Ref Des/Assembly Top")
		(33 "B.Fab" user "Ref Des/Assembly Bottom")
	)
	(footprint ""
		(layer "F.Cu")
		(at 355.009196 -26.03373)
		(property "Reference" "R4076"
			(at 0 0 0)
			(layer "F.SilkS")
			(hide yes)
			(effects
				(font
					(size 1.27 1.27)
				)
			)
		)
		(property "Value" ""
			(at 0 0 0)
			(layer "F.Fab")
			(effects
				(font
					(size 1.27 1.27)
				)
			)
		)
		(duplicate_pad_numbers_are_jumpers no)
		(fp_line
			(start -0.7874 -0.4064)
			(end 0.7874 -0.4064)
			(stroke
				(width 0.1524)
				(type default)
			)
			(layer "F.SilkS")
		)
		(fp_line
			(start -0.7874 0.4064)
			(end -0.7874 -0.4064)
			(stroke
				(width 0.1524)
				(type default)
			)
			(layer "F.SilkS")
		)
		(fp_line
			(start 0.7874 -0.4064)
			(end 0.7874 0.4064)
			(stroke
				(width 0.1524)
				(type default)
			)
			(layer "F.SilkS")
		)
		(fp_line
			(start 0.7874 0.4064)
			(end -0.7874 0.4064)
			(stroke
				(width 0.1524)
				(type default)
			)
			(layer "F.SilkS")
		)
		(fp_line
			(start -0.67945 -0.305054)
			(end -0.12065 -0.305054)
			(stroke
				(width 0.1)
				(type default)
			)
			(layer "F.Fab")
		)
		(fp_line
			(start -0.67945 0.3048)
			(end -0.67945 -0.305054)
			(stroke
				(width 0.1)
				(type default)
			)
			(layer "F.Fab")
		)
		(fp_line
			(start -0.12065 -0.305054)
			(end -0.12065 -0.2794)
			(stroke
				(width 0.1)
				(type default)
			)
			(layer "F.Fab")
		)
		(fp_line
			(start -0.12065 -0.2794)
			(end 0.12065 -0.2794)
			(stroke
				(width 0.1)
				(type default)
			)
			(layer "F.Fab")
		)
		(fp_line
			(start -0.12065 0.2794)
			(end -0.12065 0.3048)
			(stroke
				(width 0.1)
				(type default)
			)
			(layer "F.Fab")
		)
		(fp_line
			(start -0.12065 0.3048)
			(end -0.67945 0.3048)
			(stroke
				(width 0.1)
				(type default)
			)
			(layer "F.Fab")
		)
		(fp_line
			(start 0.120396 0.2794)
			(end -0.12065 0.2794)
			(stroke
				(width 0.1)
				(type default)
			)
			(layer "F.Fab")
		)
		(fp_line
			(start 0.120396 0.3048)
			(end 0.120396 0.2794)
			(stroke
				(width 0.1)
				(type default)
			)
			(layer "F.Fab")
		)
		(fp_line
			(start 0.12065 -0.3048)
			(end 0.67945 -0.3048)
			(stroke
				(width 0.1)
				(type default)
			)
			(layer "F.Fab")
		)
		(fp_line
			(start 0.12065 -0.2794)
			(end 0.12065 -0.3048)
			(stroke
				(width 0.1)
				(type default)
			)
			(layer "F.Fab")
		)
		(fp_line
			(start 0.67945 -0.3048)
			(end 0.67945 0.3048)
			(stroke
				(width 0.1)
				(type default)
			)
			(layer "F.Fab")
		)
		(fp_line
			(start 0.67945 0.3048)
			(end 0.120396 0.3048)
			(stroke
				(width 0.1)
				(type default)
			)
			(layer "F.Fab")
		)
		(pad "1" smd circle
			(at -0.40005 0)
			(size 0 0)
			(layers "F.Cu" "F.Mask" "F.Paste")
			(net "P3V3_AUX")
		)
		(pad "2" smd circle
			(at 0.40005 0)
			(size 0 0)
			(layers "F.Cu" "F.Mask" "F.Paste")
			(net "PRSNT_SSD12_R_N")
		)
	)
	(footprint ""
		(layer "F.Cu")
		(at 440.495944 -103.259128)
		(property "Reference" "C623"
			(at 0 0 0)
			(layer "F.SilkS")
			(hide yes)
			(effects
				(font
					(size 1.27 1.27)
				)
			)
		)
		(property "Value" ""
			(at 0 0 0)
			(layer "F.Fab")
			(effects
				(font
					(size 1.27 1.27)
				)
			)
		)
		(duplicate_pad_numbers_are_jumpers no)
		(fp_line
			(start -0.7874 -0.4064)
			(end 0.7874 -0.4064)
			(stroke
				(width 0.1524)
				(type default)
			)
			(layer "F.SilkS")
		)
		(fp_line
			(start -0.7874 0.4064)
			(end -0.7874 -0.4064)
			(stroke
				(width 0.1524)
				(type default)
			)
			(layer "F.SilkS")
		)
		(fp_line
			(start 0.7874 -0.4064)
			(end 0.7874 0.4064)
			(stroke
				(width 0.1524)
				(type default)
			)
			(layer "F.SilkS")
		)
		(fp_line
			(start 0.7874 0.4064)
			(end -0.7874 0.4064)
			(stroke
				(width 0.1524)
				(type default)
			)
			(layer "F.SilkS")
		)
		(fp_line
			(start -0.67945 -0.305054)
			(end -0.12065 -0.305054)
			(stroke
				(width 0.1)
				(type default)
			)
			(layer "F.Fab")
		)
		(fp_line
			(start -0.67945 0.3048)
			(end -0.67945 -0.305054)
			(stroke
				(width 0.1)
				(type default)
			)
			(layer "F.Fab")
		)
		(fp_line
			(start -0.12065 -0.305054)
			(end -0.12065 -0.2794)
			(stroke
				(width 0.1)
				(type default)
			)
			(layer "F.Fab")
		)
		(fp_line
			(start -0.12065 -0.2794)
			(end 0.12065 -0.2794)
			(stroke
				(width 0.1)
				(type default)
			)
			(layer "F.Fab")
		)
		(fp_line
			(start -0.12065 0.2794)
			(end -0.12065 0.3048)
			(stroke
				(width 0.1)
				(type default)
			)
			(layer "F.Fab")
		)
		(fp_line
			(start -0.12065 0.3048)
			(end -0.67945 0.3048)
			(stroke
				(width 0.1)
				(type default)
			)
			(layer "F.Fab")
		)
		(fp_line
			(start 0.120396 0.2794)
			(end -0.12065 0.2794)
			(stroke
				(width 0.1)
				(type default)
			)
			(layer "F.Fab")
		)
		(fp_line
			(start 0.120396 0.3048)
			(end 0.120396 0.2794)
			(stroke
				(width 0.1)
				(type default)
			)
			(layer "F.Fab")
		)
		(fp_line
			(start 0.12065 -0.3048)
			(end 0.67945 -0.3048)
			(stroke
				(width 0.1)
				(type default)
			)
			(layer "F.Fab")
		)
		(fp_line
			(start 0.12065 -0.2794)
			(end 0.12065 -0.3048)
			(stroke
				(width 0.1)
				(type default)
			)
			(layer "F.Fab")
		)
		(fp_line
			(start 0.67945 -0.3048)
			(end 0.67945 0.3048)
			(stroke
				(width 0.1)
				(type default)
			)
			(layer "F.Fab")
		)
		(fp_line
			(start 0.67945 0.3048)
			(end 0.120396 0.3048)
			(stroke
				(width 0.1)
				(type default)
			)
			(layer "F.Fab")
		)
		(pad "1" smd circle
			(at -0.40005 0)
			(size 0 0)
			(layers "F.Cu" "F.Mask" "F.Paste")
			(net "P12V_NIC7_R")
		)
		(pad "2" smd circle
			(at 0.40005 0)
			(size 0 0)
			(layers "F.Cu" "F.Mask" "F.Paste")
			(net "GND")
		)
	)
	(footprint ""
		(layer "F.Cu")
		(at 238.919512 -231.416606 90)
		(property "Reference" "R4514"
			(at 0 0 90)
			(layer "F.SilkS")
			(hide yes)
			(effects
				(font
					(size 1.27 1.27)
				)
			)
		)
		(property "Value" ""
			(at 0 0 90)
			(layer "F.Fab")
			(effects
				(font
					(size 1.27 1.27)
				)
			)
		)
		(duplicate_pad_numbers_are_jumpers no)
		(fp_line
			(start 0.7874 -0.4064)
			(end 0.7874 0.4064)
			(stroke
				(width 0.1524)
				(type default)
			)
			(layer "F.SilkS")
		)
		(fp_line
			(start -0.7874 -0.4064)
			(end 0.7874 -0.4064)
			(stroke
				(width 0.1524)
				(type default)
			)
			(layer "F.SilkS")
		)
		(fp_line
			(start 0.7874 0.4064)
			(end -0.7874 0.4064)
			(stroke
				(width 0.1524)
				(type default)
			)
			(layer "F.SilkS")
		)
		(fp_line
			(start -0.7874 0.4064)
			(end -0.7874 -0.4064)
			(stroke
				(width 0.1524)
				(type default)
			)
			(layer "F.SilkS")
		)
		(fp_line
			(start -0.12065 -0.305054)
			(end -0.12065 -0.2794)
			(stroke
				(width 0.1)
				(type default)
			)
			(layer "F.Fab")
		)
		(fp_line
			(start -0.67945 -0.305054)
			(end -0.12065 -0.305054)
			(stroke
				(width 0.1)
				(type default)
			)
			(layer "F.Fab")
		)
		(fp_line
			(start 0.67945 -0.3048)
			(end 0.67945 0.3048)
			(stroke
				(width 0.1)
				(type default)
			)
			(layer "F.Fab")
		)
		(fp_line
			(start 0.12065 -0.3048)
			(end 0.67945 -0.3048)
			(stroke
				(width 0.1)
				(type default)
			)
			(layer "F.Fab")
		)
		(fp_line
			(start 0.12065 -0.2794)
			(end 0.12065 -0.3048)
			(stroke
				(width 0.1)
				(type default)
			)
			(layer "F.Fab")
		)
		(fp_line
			(start -0.12065 -0.2794)
			(end 0.12065 -0.2794)
			(stroke
				(width 0.1)
				(type default)
			)
			(layer "F.Fab")
		)
		(fp_line
			(start 0.120396 0.2794)
			(end -0.12065 0.2794)
			(stroke
				(width 0.1)
				(type default)
			)
			(layer "F.Fab")
		)
		(fp_line
			(start -0.12065 0.2794)
			(end -0.12065 0.3048)
			(stroke
				(width 0.1)
				(type default)
			)
			(layer "F.Fab")
		)
		(fp_line
			(start 0.67945 0.3048)
			(end 0.120396 0.3048)
			(stroke
				(width 0.1)
				(type default)
			)
			(layer "F.Fab")
		)
		(fp_line
			(start 0.120396 0.3048)
			(end 0.120396 0.2794)
			(stroke
				(width 0.1)
				(type default)
			)
			(layer "F.Fab")
		)
		(fp_line
			(start -0.12065 0.3048)
			(end -0.67945 0.3048)
			(stroke
				(width 0.1)
				(type default)
			)
			(layer "F.Fab")
		)
		(fp_line
			(start -0.67945 0.3048)
			(end -0.67945 -0.305054)
			(stroke
				(width 0.1)
				(type default)
			)
			(layer "F.Fab")
		)
		(pad "1" smd circle
			(at -0.40005 0 90)
			(size 0 0)
			(layers "F.Cu" "F.Mask" "F.Paste")
			(net "SSD0_PWRDIS_BIC")
		)
		(pad "2" smd circle
			(at 0.40005 0 90)
			(size 0 0)
			(layers "F.Cu" "F.Mask" "F.Paste")
			(net "SSD0_PWRDIS_BIC_R")
		)
	)
	(footprint ""
		(layer "F.Cu")
		(at 143.030194 -284.404308 -90)
		(property "Reference" "C3189"
			(at 0 0 270)
			(layer "F.SilkS")
			(hide yes)
			(effects
				(font
					(size 1.27 1.27)
				)
			)
		)
		(property "Value" ""
			(at 0 0 270)
			(layer "F.Fab")
			(effects
				(font
					(size 1.27 1.27)
				)
			)
		)
		(duplicate_pad_numbers_are_jumpers no)
		(fp_line
			(start -1.2954 0.5842)
			(end -1.2954 -0.5842)
			(stroke
				(width 0.1524)
				(type default)
			)
			(layer "F.SilkS")
		)
		(fp_line
			(start 1.2954 0.5842)
			(end -1.2954 0.5842)
			(stroke
				(width 0.1524)
				(type default)
			)
			(layer "F.SilkS")
		)
		(fp_line
			(start -1.2954 -0.5842)
			(end 1.2954 -0.5842)
			(stroke
				(width 0.1524)
				(type default)
			)
			(layer "F.SilkS")
		)
		(fp_line
			(start 1.2954 -0.5842)
			(end 1.2954 0.5842)
			(stroke
				(width 0.1524)
				(type default)
			)
			(layer "F.SilkS")
		)
		(fp_line
			(start -0.8636 0.4572)
			(end -0.8636 0.4064)
			(stroke
				(width 0.1)
				(type default)
			)
			(layer "F.Fab")
		)
		(fp_line
			(start 0.8636 0.4572)
			(end -0.8636 0.4572)
			(stroke
				(width 0.1)
				(type default)
			)
			(layer "F.Fab")
		)
		(fp_line
			(start -1.1938 0.4064)
			(end -1.1938 -0.4064)
			(stroke
				(width 0.1)
				(type default)
			)
			(layer "F.Fab")
		)
		(fp_line
			(start -0.8636 0.4064)
			(end -1.1938 0.4064)
			(stroke
				(width 0.1)
				(type default)
			)
			(layer "F.Fab")
		)
		(fp_line
			(start 0.8636 0.4064)
			(end 0.8636 0.4572)
			(stroke
				(width 0.1)
				(type default)
			)
			(layer "F.Fab")
		)
		(fp_line
			(start 1.1938 0.4064)
			(end 0.8636 0.4064)
			(stroke
				(width 0.1)
				(type default)
			)
			(layer "F.Fab")
		)
		(fp_line
			(start -1.1938 -0.4064)
			(end -0.8636 -0.4064)
			(stroke
				(width 0.1)
				(type default)
			)
			(layer "F.Fab")
		)
		(fp_line
			(start -0.8636 -0.4064)
			(end -0.8636 -0.4572)
			(stroke
				(width 0.1)
				(type default)
			)
			(layer "F.Fab")
		)
		(fp_line
			(start 0.8636 -0.4064)
			(end 1.1938 -0.4064)
			(stroke
				(width 0.1)
				(type default)
			)
			(layer "F.Fab")
		)
		(fp_line
			(start 1.1938 -0.4064)
			(end 1.1938 0.4064)
			(stroke
				(width 0.1)
				(type default)
			)
			(layer "F.Fab")
		)
		(fp_line
			(start -0.8636 -0.4572)
			(end 0.8636 -0.4572)
			(stroke
				(width 0.1)
				(type default)
			)
			(layer "F.Fab")
		)
		(fp_line
			(start 0.8636 -0.4572)
			(end 0.8636 -0.4064)
			(stroke
				(width 0.1)
				(type default)
			)
			(layer "F.Fab")
		)
		(pad "1" smd rect
			(at -0.7366 0 180)
			(size 0.7112 0.8128)
			(layers "F.Cu" "F.Mask" "F.Paste")
			(net "P1V8_PLL0_PEX1")
		)
		(pad "2" smd rect
			(at 0.7366 0 180)
			(size 0.7112 0.8128)
			(layers "F.Cu" "F.Mask" "F.Paste")
			(net "GND")
		)
	)
	(footprint ""
		(layer "F.Cu")
		(at 326.694038 -115.394486)
		(property "Reference" "PR7102"
			(at 0 0 0)
			(layer "F.SilkS")
			(hide yes)
			(effects
				(font
					(size 1.27 1.27)
				)
			)
		)
		(property "Value" ""
			(at 0 0 0)
			(layer "F.Fab")
			(effects
				(font
					(size 1.27 1.27)
				)
			)
		)
		(duplicate_pad_numbers_are_jumpers no)
		(fp_line
			(start -0.7874 -0.4064)
			(end 0.7874 -0.4064)
			(stroke
				(width 0.1524)
				(type default)
			)
			(layer "F.SilkS")
		)
		(fp_line
			(start -0.7874 0.4064)
			(end -0.7874 -0.4064)
			(stroke
				(width 0.1524)
				(type default)
			)
			(layer "F.SilkS")
		)
		(fp_line
			(start 0.7874 -0.4064)
			(end 0.7874 0.4064)
			(stroke
				(width 0.1524)
				(type default)
			)
			(layer "F.SilkS")
		)
		(fp_line
			(start 0.7874 0.4064)
			(end -0.7874 0.4064)
			(stroke
				(width 0.1524)
				(type default)
			)
			(layer "F.SilkS")
		)
		(fp_line
			(start -0.67945 -0.305054)
			(end -0.12065 -0.305054)
			(stroke
				(width 0.1)
				(type default)
			)
			(layer "F.Fab")
		)
		(fp_line
			(start -0.67945 0.3048)
			(end -0.67945 -0.305054)
			(stroke
				(width 0.1)
				(type default)
			)
			(layer "F.Fab")
		)
		(fp_line
			(start -0.12065 -0.305054)
			(end -0.12065 -0.2794)
			(stroke
				(width 0.1)
				(type default)
			)
			(layer "F.Fab")
		)
		(fp_line
			(start -0.12065 -0.2794)
			(end 0.12065 -0.2794)
			(stroke
				(width 0.1)
				(type default)
			)
			(layer "F.Fab")
		)
		(fp_line
			(start -0.12065 0.2794)
			(end -0.12065 0.3048)
			(stroke
				(width 0.1)
				(type default)
			)
			(layer "F.Fab")
		)
		(fp_line
			(start -0.12065 0.3048)
			(end -0.67945 0.3048)
			(stroke
				(width 0.1)
				(type default)
			)
			(layer "F.Fab")
		)
		(fp_line
			(start 0.120396 0.2794)
			(end -0.12065 0.2794)
			(stroke
				(width 0.1)
				(type default)
			)
			(layer "F.Fab")
		)
		(fp_line
			(start 0.120396 0.3048)
			(end 0.120396 0.2794)
			(stroke
				(width 0.1)
				(type default)
			)
			(layer "F.Fab")
		)
		(fp_line
			(start 0.12065 -0.3048)
			(end 0.67945 -0.3048)
			(stroke
				(width 0.1)
				(type default)
			)
			(layer "F.Fab")
		)
		(fp_line
			(start 0.12065 -0.2794)
			(end 0.12065 -0.3048)
			(stroke
				(width 0.1)
				(type default)
			)
			(layer "F.Fab")
		)
		(fp_line
			(start 0.67945 -0.3048)
			(end 0.67945 0.3048)
			(stroke
				(width 0.1)
				(type default)
			)
			(layer "F.Fab")
		)
		(fp_line
			(start 0.67945 0.3048)
			(end 0.120396 0.3048)
			(stroke
				(width 0.1)
				(type default)
			)
			(layer "F.Fab")
		)
		(pad "1" smd circle
			(at -0.40005 0)
			(size 0 0)
			(layers "F.Cu" "F.Mask" "F.Paste")
			(net "P3V3_NIC5_CO_ILIMIT")
		)
		(pad "2" smd circle
			(at 0.40005 0)
			(size 0 0)
			(layers "F.Cu" "F.Mask" "F.Paste")
			(net "GND")
		)
	)
	(footprint ""
		(layer "F.Cu")
		(at 258.242562 -211.749386)
		(property "Reference" "C2491"
			(at 0 0 0)
			(layer "F.SilkS")
			(hide yes)
			(effects
				(font
					(size 1.27 1.27)
				)
			)
		)
		(property "Value" ""
			(at 0 0 0)
			(layer "F.Fab")
			(effects
				(font
					(size 1.27 1.27)
				)
			)
		)
		(duplicate_pad_numbers_are_jumpers no)
		(fp_line
			(start -0.7874 -0.4064)
			(end 0.7874 -0.4064)
			(stroke
				(width 0.1524)
				(type default)
			)
			(layer "F.SilkS")
		)
		(fp_line
			(start -0.7874 0.4064)
			(end -0.7874 -0.4064)
			(stroke
				(width 0.1524)
				(type default)
			)
			(layer "F.SilkS")
		)
		(fp_line
			(start 0.7874 -0.4064)
			(end 0.7874 0.4064)
			(stroke
				(width 0.1524)
				(type default)
			)
			(layer "F.SilkS")
		)
		(fp_line
			(start 0.7874 0.4064)
			(end -0.7874 0.4064)
			(stroke
				(width 0.1524)
				(type default)
			)
			(layer "F.SilkS")
		)
		(fp_line
			(start -0.67945 -0.305054)
			(end -0.12065 -0.305054)
			(stroke
				(width 0.1)
				(type default)
			)
			(layer "F.Fab")
		)
		(fp_line
			(start -0.67945 0.3048)
			(end -0.67945 -0.305054)
			(stroke
				(width 0.1)
				(type default)
			)
			(layer "F.Fab")
		)
		(fp_line
			(start -0.12065 -0.305054)
			(end -0.12065 -0.2794)
			(stroke
				(width 0.1)
				(type default)
			)
			(layer "F.Fab")
		)
		(fp_line
			(start -0.12065 -0.2794)
			(end 0.12065 -0.2794)
			(stroke
				(width 0.1)
				(type default)
			)
			(layer "F.Fab")
		)
		(fp_line
			(start -0.12065 0.2794)
			(end -0.12065 0.3048)
			(stroke
				(width 0.1)
				(type default)
			)
			(layer "F.Fab")
		)
		(fp_line
			(start -0.12065 0.3048)
			(end -0.67945 0.3048)
			(stroke
				(width 0.1)
				(type default)
			)
			(layer "F.Fab")
		)
		(fp_line
			(start 0.120396 0.2794)
			(end -0.12065 0.2794)
			(stroke
				(width 0.1)
				(type default)
			)
			(layer "F.Fab")
		)
		(fp_line
			(start 0.120396 0.3048)
			(end 0.120396 0.2794)
			(stroke
				(width 0.1)
				(type default)
			)
			(layer "F.Fab")
		)
		(fp_line
			(start 0.12065 -0.3048)
			(end 0.67945 -0.3048)
			(stroke
				(width 0.1)
				(type default)
			)
			(layer "F.Fab")
		)
		(fp_line
			(start 0.12065 -0.2794)
			(end 0.12065 -0.3048)
			(stroke
				(width 0.1)
				(type default)
			)
			(layer "F.Fab")
		)
		(fp_line
			(start 0.67945 -0.3048)
			(end 0.67945 0.3048)
			(stroke
				(width 0.1)
				(type default)
			)
			(layer "F.Fab")
		)
		(fp_line
			(start 0.67945 0.3048)
			(end 0.120396 0.3048)
			(stroke
				(width 0.1)
				(type default)
			)
			(layer "F.Fab")
		)
		(pad "1" smd circle
			(at -0.40005 0)
			(size 0 0)
			(layers "F.Cu" "F.Mask" "F.Paste")
			(net "PWR_EN_P1V2_AUX_R")
		)
		(pad "2" smd circle
			(at 0.40005 0)
			(size 0 0)
			(layers "F.Cu" "F.Mask" "F.Paste")
			(net "GND")
		)
	)
)
